# S9S_MB_2U (Grand Teton) — schematic parts with pin connectivity, parts 1614–1614 of 6093; source: Cadence DE-HDL packaged netlist (pstxprt.dat, pstxnet.dat, pstchip.dat)

J21  SCONN288_ADR50017P130CC  SCONN288_ADR50017-P130CC IO  pkg DDR288S_1-1VXB  page 102
  1  VIN_BULK0  POWER  = P12V_S3_AUX_CPU1_NVDIMM
  2  RFU0  TRI  = TP_CHC_CPU1_DIMM1_FRU_0
  3  VIN_MGMT  POWER  = P3V3_AUX
  4  HSCL  IN  = I3C_SPD_DDRABCD_CPU1_LVC1_SCL_4
  5  HSDA  BI  = I3C_SPD_DDRABCD_CPU1_LVC1_SDA
  6  VSS0  POWER  = GND
  7  DQ0_A  BI  = M_C_CPU1_SA_DQ<0>
  8  VSS1  POWER  = GND
  9  DQ1_A  BI  = M_C_CPU1_SA_DQ<1>
  10  VSS2  POWER  = GND
  11  DQS0_A_T  BI  = M_C_CPU1_SA_DQS_DP<0>
  12  DQS0_A_C  BI  = M_C_CPU1_SA_DQS_DN<0>
  13  VSS3  POWER  = GND
  14  DQ4_A  BI  = M_C_CPU1_SA_DQ<4>
  15  VSS4  POWER  = GND
  16  DQ5_A  BI  = M_C_CPU1_SA_DQ<5>
  17  VSS5  POWER  = GND
  18  DQ8_A  BI  = M_C_CPU1_SA_DQ<8>
  19  VSS6  POWER  = GND
  20  DQ9_A  BI  = M_C_CPU1_SA_DQ<9>
  21  VSS7  POWER  = GND
  22  DQS1_A_T  BI  = M_C_CPU1_SA_DQS_DP<1>
  23  DQS1_A_C  BI  = M_C_CPU1_SA_DQS_DN<1>
  24  VSS8  POWER  = GND
  25  DQ12_A  BI  = M_C_CPU1_SA_DQ<12>
  26  VSS9  POWER  = GND
  27  DQ13_A  BI  = M_C_CPU1_SA_DQ<13>
  28  VSS10  POWER  = GND
  29  DQ16_A  BI  = M_C_CPU1_SA_DQ<16>
  30  VSS11  POWER  = GND
  31  DQ17_A  BI  = M_C_CPU1_SA_DQ<17>
  32  VSS12  POWER  = GND
  33  DQS2_A_T  BI  = M_C_CPU1_SA_DQS_DP<2>
  34  DQS2_A_C  BI  = M_C_CPU1_SA_DQS_DN<2>
  35  VSS13  POWER  = GND
  36  DQ20_A  BI  = M_C_CPU1_SA_DQ<20>
  37  VSS14  POWER  = GND
  38  DQ21_A  BI  = M_C_CPU1_SA_DQ<21>
  39  VSS15  POWER  = GND
  40  DQ24_A  BI  = M_C_CPU1_SA_DQ<24>
  41  VSS16  POWER  = GND
  42  DQ25_A  BI  = M_C_CPU1_SA_DQ<25>
  43  VSS17  POWER  = GND
  44  DQS3_A_T  BI  = M_C_CPU1_SA_DQS_DP<3>
  45  DQS3_A_C  BI  = M_C_CPU1_SA_DQS_DN<3>
  46  VSS18  POWER  = GND
  47  DQ28_A  BI  = M_C_CPU1_SA_DQ<28>
  48  VSS19  POWER  = GND
  49  DQ29_A  BI  = M_C_CPU1_SA_DQ<29>
  50  VSS20  POWER  = GND
  51  CB0_A  BI  = M_C_CPU1_SA_CB<0>
  52  VSS21  POWER  = GND
  53  CB1_A  BI  = M_C_CPU1_SA_CB<1>
  54  VSS22  POWER  = GND
  55  DQS4_A_T  BI  = M_C_CPU1_SA_DQS_DP<4>
  56  DQS4_A_C  BI  = M_C_CPU1_SA_DQS_DN<4>
  57  VSS23  POWER  = GND
  58  CB4_A  BI  = M_C_CPU1_SA_CB<4>
  59  VSS24  POWER  = GND
  60  CB5_A  BI  = M_C_CPU1_SA_CB<5>
  61  VSS25  POWER  = GND
  62  ALERT_N  OUT  = M_C_CPU1_ALERT_N
  63  VSS26  POWER  = GND
  64  CS0_A_N  IN  = M_C_CPU1_SA_CS_N<0>
  65  VSS27  POWER  = GND
  66  CA0_A  IN  = M_C_CPU1_SA_CA<0>
  67  VSS28  POWER  = GND
  68  CA2_A  IN  = M_C_CPU1_SA_CA<2>
  69  VSS29  POWER  = GND
  70  CA4_A  IN  = M_C_CPU1_SA_CA<4>
  71  VSS30  POWER  = GND
  72  CA6_A  IN  = M_C_CPU1_SA_CA<6>
  73  VSS31  POWER  = GND
  74  PAR_A  IN  = M_C_CPU1_SA_PAR
  75  VSS32  POWER  = GND
  76  CA0_B  IN  = M_C_CPU1_SB_CA<0>
  77  VSS33  POWER  = GND
  78  CA2_B  IN  = M_C_CPU1_SB_CA<2>
  79  VSS34  POWER  = GND
  80  CA4_B  IN  = M_C_CPU1_SB_CA<4>
  81  VSS35  POWER  = GND
  82  CA6_B  IN  = M_C_CPU1_SB_CA<6>
  83  VSS36  POWER  = GND
  84  CS0_B_N  IN  = M_C_CPU1_SB_CS_N<0>
  85  VSS37  POWER  = GND
  86  \lbd||rsp_a_n\  OUT  = M_C_CPU1_SA_RSP<0>
  87  \lbs||rsp_b_n\  OUT  = M_C_CPU1_SB_RSP<0>
  88  VSS38  POWER  = GND
  89  CB4_B  BI  = M_C_CPU1_SB_CB<4>
  90  VSS39  POWER  = GND
  91  CB5_B  BI  = M_C_CPU1_SB_CB<5>
  92  VSS40  POWER  = GND
  93  \dqs9_b_t||tdqs9_b_t||dbi4_b_n\  BI  = M_C_CPU1_SB_DQS_DP<9>
  94  \dqs9_b_c||tdqs9_b_c\  BI  = M_C_CPU1_SB_DQS_DN<9>
  95  VSS41  POWER  = GND
  96  CB0_B  BI  = M_C_CPU1_SB_CB<0>
  97  VSS42  POWER  = GND
  98  CB1_B  BI  = M_C_CPU1_SB_CB<1>
  99  VSS43  POWER  = GND
  100  DQ0_B  BI  = M_C_CPU1_SB_DQ<0>
  101  VSS44  POWER  = GND
  102  DQ1_B  BI  = M_C_CPU1_SB_DQ<1>
  103  VSS45  POWER  = GND
  104  DQS0_B_T  BI  = M_C_CPU1_SB_DQS_DP<0>
  105  DQS0_B_C  BI  = M_C_CPU1_SB_DQS_DN<0>
  106  VSS46  POWER  = GND
  107  DQ4_B  BI  = M_C_CPU1_SB_DQ<4>
  108  VSS47  POWER  = GND
  109  DQ5_B  BI  = M_C_CPU1_SB_DQ<5>
  110  VSS48  POWER  = GND
  111  DQ8_B  BI  = M_C_CPU1_SB_DQ<8>
  112  VSS49  POWER  = GND
  113  DQ9_B  BI  = M_C_CPU1_SB_DQ<9>
  114  VSS50  POWER  = GND
  115  DQS1_B_T  BI  = M_C_CPU1_SB_DQS_DP<1>
  116  DQS1_B_C  BI  = M_C_CPU1_SB_DQS_DN<1>
  117  VSS51  POWER  = GND
  118  DQ12_B  BI  = M_C_CPU1_SB_DQ<12>
  119  VSS52  POWER  = GND
  120  DQ13_B  BI  = M_C_CPU1_SB_DQ<13>
  121  VSS53  POWER  = GND
  122  DQ16_B  BI  = M_C_CPU1_SB_DQ<16>
  123  VSS54  POWER  = GND
  124  DQ17_B  BI  = M_C_CPU1_SB_DQ<17>
  125  VSS55  POWER  = GND
  126  DQS2_B_T  BI  = M_C_CPU1_SB_DQS_DP<2>
  127  DQS2_B_C  BI  = M_C_CPU1_SB_DQS_DN<2>
  128  VSS56  POWER  = GND
  129  DQ20_B  BI  = M_C_CPU1_SB_DQ<20>
  130  VSS57  POWER  = GND
  131  DQ21_B  BI  = M_C_CPU1_SB_DQ<21>
  132  VSS58  POWER  = GND
  133  DQ24_B  BI  = M_C_CPU1_SB_DQ<24>
  134  VSS59  POWER  = GND
  135  DQ25_B  BI  = M_C_CPU1_SB_DQ<25>
  136  VSS60  POWER  = GND
  137  DQS3_B_T  BI  = M_C_CPU1_SB_DQS_DP<3>
  138  DQS3_B_C  BI  = M_C_CPU1_SB_DQS_DN<3>
  139  VSS61  POWER  = GND
  140  DQ28_B  BI  = M_C_CPU1_SB_DQ<28>
  141  VSS62  POWER  = GND
  142  DQ29_B  BI  = M_C_CPU1_SB_DQ<29>
  143  VSS63  POWER  = GND
  144  RFU1  TRI  = TP_CHC_CPU1_DIMM1_FRU_1
  145  VIN_BULK1  POWER  = P12V_S3_AUX_CPU1_NVDIMM
  146  VIN_BULK2  POWER  = P12V_S3_AUX_CPU1_NVDIMM
  147  \pwr_good||fail_n\  BI  = PWRGD_CHC_CPU1_DIMM1
  148  HSA  IN  = PD_CHC_CPU1_DIMM1_SAA
  149  RFU2  TRI  = TP_CHC_CPU1_DIMM1_FRU_2
  150  RFU3  TRI  = TP_CHC_CPU1_DIMM1_FRU_3
  151  VSS64  POWER  = GND
  152  DQ2_A  BI  = M_C_CPU1_SA_DQ<2>
  153  VSS65  POWER  = GND
  154  DQ3_A  BI  = M_C_CPU1_SA_DQ<3>
  155  VSS66  POWER  = GND
  156  \dqs5_a_c||tdqs5_a_c||dqs5_a_t||tdqs5_a_t\  BI  = M_C_CPU1_SA_DQS_DN<5>
  157  \dqs5_a_t||tdqs5_a_t\  BI  = M_C_CPU1_SA_DQS_DP<5>
  158  VSS67  POWER  = GND
  159  DQ6_A  BI  = M_C_CPU1_SA_DQ<6>
  160  VSS68  POWER  = GND
  161  DQ7_A  BI  = M_C_CPU1_SA_DQ<7>
  162  VSS69  POWER  = GND
  163  DQ10_A  BI  = M_C_CPU1_SA_DQ<10>
  164  VSS70  POWER  = GND
  165  DQ11_A  BI  = M_C_CPU1_SA_DQ<11>
  166  VSS71  POWER  = GND
  167  \dqs6_a_c||tdqs6_a_c||dqs6_a_t||tdqs6_a_t\  BI  = M_C_CPU1_SA_DQS_DN<6>
  168  \dqs6_a_t||tdqs6_a_t\  BI  = M_C_CPU1_SA_DQS_DP<6>
  169  VSS72  POWER  = GND
  170  DQ14_A  BI  = M_C_CPU1_SA_DQ<14>
  171  VSS73  POWER  = GND
  172  DQ15_A  BI  = M_C_CPU1_SA_DQ<15>
  173  VSS74  POWER  = GND
  174  DQ18_A  BI  = M_C_CPU1_SA_DQ<18>
  175  VSS75  POWER  = GND
  176  DQ19_A  BI  = M_C_CPU1_SA_DQ<19>
  177  VSS76  POWER  = GND
  178  \dqs7_a_c||tdqs7_a_c\  BI  = M_C_CPU1_SA_DQS_DN<7>
  179  \dqs7_a_t||tdqs7_a_t\  BI  = M_C_CPU1_SA_DQS_DP<7>
  180  VSS77  POWER  = GND
  181  DQ22_A  BI  = M_C_CPU1_SA_DQ<22>
  182  VSS78  POWER  = GND
  183  DQ23_A  BI  = M_C_CPU1_SA_DQ<23>
  184  VSS79  POWER  = GND
  185  DQ26_A  BI  = M_C_CPU1_SA_DQ<26>
  186  VSS80  POWER  = GND
  187  DQ27_A  BI  = M_C_CPU1_SA_DQ<27>
  188  VSS81  POWER  = GND
  189  \dqs8_a_c||tdqs8_a_c\  BI  = M_C_CPU1_SA_DQS_DN<8>
  190  \dqs8_a_t||tdqs8_a_t\  BI  = M_C_CPU1_SA_DQS_DP<8>
  191  VSS82  POWER  = GND
  192  DQ30_A  BI  = M_C_CPU1_SA_DQ<30>
  193  VSS83  POWER  = GND
  194  DQ31_A  BI  = M_C_CPU1_SA_DQ<31>
  195  VSS84  POWER  = GND
  196  CB2_A  BI  = M_C_CPU1_SA_CB<2>
  197  VSS85  POWER  = GND
  198  CB3_A  BI  = M_C_CPU1_SA_CB<3>
  199  VSS86  POWER  = GND
  200  \dqs9_a_c||tdqs9_a_c\  BI  = M_C_CPU1_SA_DQS_DN<9>
  201  \dqs9_a_t||tdqs9_a_t\  BI  = M_C_CPU1_SA_DQS_DP<9>
  202  VSS87  POWER  = GND
  203  CB6_A  BI  = M_C_CPU1_SA_CB<6>
  204  VSS88  POWER  = GND
  205  CB7_A  BI  = M_C_CPU1_SA_CB<7>
  206  VSS89  POWER  = GND
  207  RESET_N  IN  = RST_M_CD_CPU1_FPGA_N
  208  VSS90  POWER  = GND
  209  CS1_A_N  IN  = M_C_CPU1_SA_CS_N<1>
  210  VSS91  POWER  = GND
  211  CA1_A  IN  = M_C_CPU1_SA_CA<1>
  212  VSS92  POWER  = GND
  213  CA3_A  IN  = M_C_CPU1_SA_CA<3>
  214  VSS93  POWER  = GND
  215  CA5_A  IN  = M_C_CPU1_SA_CA<5>
  216  VSS94  POWER  = GND
  217  CK_T  IN  = M_C_CPU1_CLK_DP<0>
  218  CK_C  IN  = M_C_CPU1_CLK_DN<0>
  219  VSS95  POWER  = GND
  220  RFU4  TRI  = TP_CHC_CPU1_DIMM1_FRU_4
  221  CA1_B  IN  = M_C_CPU1_SB_CA<1>
  222  VSS96  POWER  = GND
  223  CA3_B  IN  = M_C_CPU1_SB_CA<3>
  224  VSS97  POWER  = GND
  225  CA5_B  IN  = M_C_CPU1_SB_CA<5>
  226  VSS98  POWER  = GND
  227  PAR_B  IN  = M_C_CPU1_SB_PAR
  228  VSS99  POWER  = GND
  229  CS1_B_N  IN  = M_C_CPU1_SB_CS_N<1>
  230  VSS100  POWER  = GND
  231  RFU5  TRI  = TP_CHC_CPU1_DIMM1_FRU_5
  232  RFU6  TRI  = TP_CHC_CPU1_DIMM1_FRU_6
  233  VSS101  POWER  = GND
  234  CB6_B  BI  = M_C_CPU1_SB_CB<6>
  235  VSS102  POWER  = GND
  236  CB7_B  BI  = M_C_CPU1_SB_CB<7>
  237  VSS103  POWER  = GND
  238  DQS4_B_C  BI  = M_C_CPU1_SB_DQS_DN<4>
  239  DQS4_B_T  BI  = M_C_CPU1_SB_DQS_DP<4>
  240  VSS104  POWER  = GND
  241  CB2_B  BI  = M_C_CPU1_SB_CB<2>
  242  VSS105  POWER  = GND
  243  CB3_B  BI  = M_C_CPU1_SB_CB<3>
  244  VSS106  POWER  = GND
  245  DQ2_B  BI  = M_C_CPU1_SB_DQ<2>
  246  VSS107  POWER  = GND
  247  DQ3_B  BI  = M_C_CPU1_SB_DQ<3>
  248  VSS108  POWER  = GND
  249  \dqs5_b_c||tdqs5_b_c\  BI  = M_C_CPU1_SB_DQS_DN<5>
  250  \dqs5_b_t||tdqs5_b_t\  BI  = M_C_CPU1_SB_DQS_DP<5>
  251  VSS109  POWER  = GND
  252  DQ6_B  BI  = M_C_CPU1_SB_DQ<6>
  253  VSS110  POWER  = GND
  254  DQ7_B  BI  = M_C_CPU1_SB_DQ<7>
  255  VSS111  POWER  = GND
  256  DQ10_B  BI  = M_C_CPU1_SB_DQ<10>
  257  VSS112  POWER  = GND
  258  DQ11_B  BI  = M_C_CPU1_SB_DQ<11>
  259  VSS113  POWER  = GND
  260  \dqs6_b_c||tdqs6_b_c\  BI  = M_C_CPU1_SB_DQS_DN<6>
  261  \dqs6_b_t||tdqs6_b_t\  BI  = M_C_CPU1_SB_DQS_DP<6>
  262  VSS114  POWER  = GND
  263  DQ14_B  BI  = M_C_CPU1_SB_DQ<14>
  264  VSS115  POWER  = GND
  265  DQ15_B  BI  = M_C_CPU1_SB_DQ<15>
  266  VSS116  POWER  = GND
  267  DQ18_B  BI  = M_C_CPU1_SB_DQ<18>
  268  VSS117  POWER  = GND
  269  DQ19_B  BI  = M_C_CPU1_SB_DQ<19>
  270  VSS118  POWER  = GND
  271  \dqs7_b_c||tdqs7_b_c\  BI  = M_C_CPU1_SB_DQS_DN<7>
  272  \dqs7_b_t||tdqs7_b_t\  BI  = M_C_CPU1_SB_DQS_DP<7>
  273  VSS119  POWER  = GND
  274  DQ22_B  BI  = M_C_CPU1_SB_DQ<22>
  275  VSS120  POWER  = GND
  276  DQ23_B  BI  = M_C_CPU1_SB_DQ<23>
  277  VSS121  POWER  = GND
  278  DQ26_B  BI  = M_C_CPU1_SB_DQ<26>
  279  VSS122  POWER  = GND
  280  DQ27_B  BI  = M_C_CPU1_SB_DQ<27>
  281  VSS123  POWER  = GND
  282  \dqs8_b_c||tdqs8_b_c\  BI  = M_C_CPU1_SB_DQS_DN<8>
  283  \dqs8_b_t||tdqs8_b_t\  BI  = M_C_CPU1_SB_DQS_DP<8>
  284  VSS124  POWER  = GND
  285  DQ30_B  BI  = M_C_CPU1_SB_DQ<30>
  286  VSS125  POWER  = GND
  287  DQ31_B  BI  = M_C_CPU1_SB_DQ<31>
  288  VSS126  POWER  = GND
  G1  G1  POWER  = GND
  G2  G2  POWER  = GND
  G3  G3  POWER  = GND
